# BASEBOARD_FAB2 (Tioga Pass) — schematic netlist excerpt (pin names and nets, part order shuffled) for the footprints in the layout excerpt that follows; sources: Cadence DE-HDL packaged netlist, KiCad conversion of Wiwynn_Tioga_Pass_MB.brd

R1M9  RES  20.0 1% CHIP  pkg 0402  page 167 : A = SMB_SENSOR_TMP421_1_SDA ; B = SMB_SENSOR_STBY_LVC3_SDA
C8B12  CAP  10UF 16V 10% X6S  pkg 0805  page 198 : A = P5V_STBY ; B = GND
RT40  RES  0 5.0% CHIP  pkg 0603  page 205 : A = VR_PVSA_CPU0_BOOT ; B = VR_PVSA_CPU0_BOOT_R

(kicad_pcb
	(version 20260206)
	(generator "pcbnew")
	(generator_version "10.0")
	(general
		(thickness 1.6)
		(legacy_teardrops no)
	)
	(paper "A4")
	(title_block
		(title "Wiwynn_Tioga_Pass_MB.brd")
		(comment 1 "Tioga Pass / footprints 1603-1605 of 4770")
	)
	(layers
		(0 "F.Cu" signal "TOP")
		(4 "In1.Cu" signal "L2GND")
		(6 "In2.Cu" signal "L3")
		(8 "In3.Cu" signal "L4GND")
		(10 "In4.Cu" signal "L5")
		(12 "In5.Cu" signal "L6GND")
		(14 "In6.Cu" signal "L7VCC")
		(16 "In7.Cu" signal "L8VCC")
		(18 "In8.Cu" signal "L9GND")
		(20 "In9.Cu" signal "L10")
		(22 "In10.Cu" signal "L11GND")
		(24 "In11.Cu" signal "L12")
		(26 "In12.Cu" signal "L13GND")
		(2 "B.Cu" signal "BOTTOM")
		(9 "F.Adhes" user "F.Adhesive")
		(11 "B.Adhes" user "B.Adhesive")
		(13 "F.Paste" user "Package Geometry/Pastemask Top")
		(15 "B.Paste" user "Package Geometry/Pastemask Bottom")
		(5 "F.SilkS" user "Ref Des/Silkscreen Top")
		(7 "B.SilkS" user "Ref Des/Silkscreen Bottom")
		(1 "F.Mask" user "Board Geometry/Soldermask Top")
		(3 "B.Mask" user "Board Geometry/Soldermask Bottom")
		(17 "Dwgs.User" user "User.Drawings")
		(19 "Cmts.User" user "User.Comments")
		(21 "Eco1.User" user "User.Eco1")
		(23 "Eco2.User" user "User.Eco2")
		(25 "Edge.Cuts" user "Board Geometry/Outline")
		(27 "Margin" user)
		(31 "F.CrtYd" user "Package Geometry/Place Bound Top")
		(29 "B.CrtYd" user "Package Geometry/Place Bound Bottom")
		(35 "F.Fab" user "Ref Des/Assembly Top")
		(33 "B.Fab" user "Ref Des/Assembly Bottom")
	)
	(footprint ""
		(layer "F.Cu")
		(at 494.18494 -124.25172 90)
		(property "Reference" "R1M9"
			(at 0 0 90)
			(layer "F.SilkS")
			(hide yes)
			(effects
				(font
					(size 1.27 1.27)
				)
			)
		)
		(property "Value" ""
			(at 0 0 90)
			(layer "F.Fab")
			(effects
				(font
					(size 1.27 1.27)
				)
			)
		)
		(duplicate_pad_numbers_are_jumpers no)
		(fp_rect
			(start 0.2794 -0.1016)
			(end -0.2794 0.9906)
			(stroke
				(width 0)
				(type default)
			)
			(fill no)
			(layer "F.CrtYd")
		)
		(fp_line
			(start 0.2794 -0.1016)
			(end -0.2794 -0.1016)
			(stroke
				(width 0.1)
				(type default)
			)
			(layer "F.Fab")
		)
		(fp_line
			(start -0.2794 -0.1016)
			(end -0.2794 0.9906)
			(stroke
				(width 0.1)
				(type default)
			)
			(layer "F.Fab")
		)
		(fp_line
			(start 0.2794 0.9906)
			(end 0.2794 -0.1016)
			(stroke
				(width 0.1)
				(type default)
			)
			(layer "F.Fab")
		)
		(fp_line
			(start -0.2794 0.9906)
			(end 0.2794 0.9906)
			(stroke
				(width 0.1)
				(type default)
			)
			(layer "F.Fab")
		)
		(pad "1" smd rect
			(at 0 0 90)
			(size 0.508 0.508)
			(layers "F.Cu" "F.Mask" "F.Paste")
			(net "SMB_SENSOR_TMP421_1_SDA")
		)
		(pad "2" smd rect
			(at 0 0.889 90)
			(size 0.508 0.508)
			(layers "F.Cu" "F.Mask" "F.Paste")
			(net "SMB_SENSOR_STBY_LVC3_SDA")
		)
		(zone
			(layer "F.Cu")
			(hatch none 0.5)
			(connect_pads
				(clearance 0)
			)
			(min_thickness 0.25)
			(keepout
				(tracks not_allowed)
				(vias allowed)
				(pads allowed)
				(copperpour not_allowed)
				(footprints allowed)
			)
			(placement
				(enabled no)
				(sheetname "")
			)
			(fill
				(thermal_gap 0.5)
				(thermal_bridge_width 0.5)
				(island_removal_mode 0)
			)
			(polygon
				(pts
					(xy 494.43894 -124.50572) (xy 494.43894 -123.99772) (xy 494.81994 -123.99772) (xy 494.81994 -124.50572)
				)
			)
		)
		(zone
			(layer "F.Cu")
			(hatch none 0.5)
			(connect_pads
				(clearance 0)
			)
			(min_thickness 0.25)
			(keepout
				(tracks allowed)
				(vias not_allowed)
				(pads allowed)
				(copperpour not_allowed)
				(footprints allowed)
			)
			(placement
				(enabled no)
				(sheetname "")
			)
			(fill
				(thermal_gap 0.5)
				(thermal_bridge_width 0.5)
				(island_removal_mode 0)
			)
			(polygon
				(pts
					(xy 494.43894 -124.50572) (xy 494.43894 -123.99772) (xy 494.81994 -123.99772) (xy 494.81994 -124.50572)
				)
			)
		)
	)
	(footprint ""
		(layer "F.Cu")
		(at 193.0146 -98.7298 90)
		(property "Reference" "RT40"
			(at 1.01473 0.656336 0)
			(unlocked yes)
			(layer "F.SilkS")
			(effects
				(font
					(size 0.4064 0.254)
					(thickness 0.1524)
				)
			)
		)
		(property "Value" ""
			(at 0 0 90)
			(layer "F.Fab")
			(effects
				(font
					(size 1.27 1.27)
				)
			)
		)
		(duplicate_pad_numbers_are_jumpers no)
		(fp_poly
			(pts
				(xy -0.4953 -0.2032) (xy 0.4953 -0.2032) (xy 0.4953 1.6002) (xy -0.4953 1.6002)
			)
			(stroke
				(width 0)
				(type default)
			)
			(fill no)
			(layer "F.CrtYd")
		)
		(fp_line
			(start 0.4953 -0.2032)
			(end 0.4953 1.6002)
			(stroke
				(width 0.1)
				(type default)
			)
			(layer "F.Fab")
		)
		(fp_line
			(start -0.4953 -0.2032)
			(end 0.4953 -0.2032)
			(stroke
				(width 0.1)
				(type default)
			)
			(layer "F.Fab")
		)
		(fp_line
			(start 0.4953 1.6002)
			(end -0.4953 1.6002)
			(stroke
				(width 0.1)
				(type default)
			)
			(layer "F.Fab")
		)
		(fp_line
			(start -0.4953 1.6002)
			(end -0.4953 -0.2032)
			(stroke
				(width 0.1)
				(type default)
			)
			(layer "F.Fab")
		)
		(pad "1" smd rect
			(at 0 0 90)
			(size 0.762 0.889)
			(layers "F.Cu" "F.Mask" "F.Paste")
			(net "VR_PVSA_CPU0_BOOT")
		)
		(pad "2" smd rect
			(at 0 1.397 90)
			(size 0.762 0.889)
			(layers "F.Cu" "F.Mask" "F.Paste")
			(net "VR_PVSA_CPU0_BOOT_R")
		)
		(zone
			(layer "F.Cu")
			(hatch none 0.5)
			(connect_pads
				(clearance 0)
			)
			(min_thickness 0.25)
			(keepout
				(tracks allowed)
				(vias not_allowed)
				(pads allowed)
				(copperpour not_allowed)
				(footprints allowed)
			)
			(placement
				(enabled no)
				(sheetname "")
			)
			(fill
				(thermal_gap 0.5)
				(thermal_bridge_width 0.5)
				(island_removal_mode 0)
			)
			(polygon
				(pts
					(xy 193.9671 -99.1108) (xy 193.4591 -99.1108) (xy 193.4591 -98.3488) (xy 193.9671 -98.3488)
				)
			)
		)
		(zone
			(layer "F.Cu")
			(hatch none 0.5)
			(connect_pads
				(clearance 0)
			)
			(min_thickness 0.25)
			(keepout
				(tracks not_allowed)
				(vias allowed)
				(pads allowed)
				(copperpour not_allowed)
				(footprints allowed)
			)
			(placement
				(enabled no)
				(sheetname "")
			)
			(fill
				(thermal_gap 0.5)
				(thermal_bridge_width 0.5)
				(island_removal_mode 0)
			)
			(polygon
				(pts
					(xy 193.9671 -98.3488) (xy 193.9671 -99.1108) (xy 193.4591 -99.1108) (xy 193.4591 -98.3488)
				)
			)
		)
	)
	(footprint ""
		(layer "F.Cu")
		(at 431.378868 -125.941582 -90)
		(property "Reference" "C8B12"
			(at 0 0 270)
			(layer "F.SilkS")
			(hide yes)
			(effects
				(font
					(size 1.27 1.27)
				)
			)
		)
		(property "Value" ""
			(at 0 0 270)
			(layer "F.Fab")
			(effects
				(font
					(size 1.27 1.27)
				)
			)
		)
		(duplicate_pad_numbers_are_jumpers no)
		(fp_poly
			(pts
				(xy -0.7239 -0.2159) (xy 0.7239 -0.2159) (xy 0.7239 1.9939) (xy -0.7239 1.9939)
			)
			(stroke
				(width 0)
				(type default)
			)
			(fill no)
			(layer "F.CrtYd")
		)
		(fp_line
			(start -0.7239 1.9939)
			(end 0.7239 1.9939)
			(stroke
				(width 0.1)
				(type default)
			)
			(layer "F.Fab")
		)
		(fp_line
			(start 0.7239 1.9939)
			(end 0.7239 -0.2159)
			(stroke
				(width 0.1)
				(type default)
			)
			(layer "F.Fab")
		)
		(fp_line
			(start -0.7239 -0.2159)
			(end -0.7239 1.9939)
			(stroke
				(width 0.1)
				(type default)
			)
			(layer "F.Fab")
		)
		(fp_line
			(start 0.7239 -0.2159)
			(end -0.7239 -0.2159)
			(stroke
				(width 0.1)
				(type default)
			)
			(layer "F.Fab")
		)
		(pad "1" smd rect
			(at 0 0 270)
			(size 1.27 1.016)
			(layers "F.Cu" "F.Mask" "F.Paste")
			(net "P5V_STBY")
		)
		(pad "2" smd rect
			(at 0 1.778 270)
			(size 1.27 1.016)
			(layers "F.Cu" "F.Mask" "F.Paste")
			(net "GND")
		)
		(zone
			(layer "F.Cu")
			(hatch none 0.5)
			(connect_pads
				(clearance 0)
			)
			(min_thickness 0.25)
			(keepout
				(tracks not_allowed)
				(vias allowed)
				(pads allowed)
				(copperpour not_allowed)
				(footprints allowed)
			)
			(placement
				(enabled no)
				(sheetname "")
			)
			(fill
				(thermal_gap 0.5)
				(thermal_bridge_width 0.5)
				(island_removal_mode 0)
			)
			(polygon
				(pts
					(xy 430.870868 -126.576582) (xy 430.870868 -125.306582) (xy 430.108868 -125.306582) (xy 430.108868 -126.576582)
				)
			)
		)
	)
)
